# T6G (Grand Teton) — schematic netlist excerpt (pin names and nets, part order shuffled) for the footprints in the layout excerpt that follows; sources: Cadence DE-HDL packaged netlist, KiCad conversion of 04192023_DAF0TMB3IC0_F0TG_MB_C_brd_V02_OCP.brd

R4191  Q_RES  1K 1% CHIP  pkg 0402LF  page 235 : A = U270_0_ADD2 ; B = GND
R4182  Q_RES  33.2 1% CHIP  pkg 0402LF  page 235 : A = SMB_LM75_1_3V3AUX_SDA ; B = SMB_LM75_1_3V3AUX_SDA_R1

(kicad_pcb
	(version 20260206)
	(generator "pcbnew")
	(generator_version "10.0")
	(general
		(thickness 1.6)
		(legacy_teardrops no)
	)
	(paper "A4")
	(title_block
		(title "04192023_DAF0TMB3IC0_F0TG_MB_C_brd_V02_OCP.brd")
		(comment 1 "Grand Teton / footprints 2678-2679 of 8354")
	)
	(layers
		(0 "F.Cu" signal "TOP")
		(4 "In1.Cu" signal "GND")
		(6 "In2.Cu" signal "IN1")
		(8 "In3.Cu" signal "GND1")
		(10 "In4.Cu" signal "IN2")
		(12 "In5.Cu" signal "GND2")
		(14 "In6.Cu" signal "IN3")
		(16 "In7.Cu" signal "GND3")
		(18 "In8.Cu" signal "VCC")
		(20 "In9.Cu" signal "VCC1")
		(22 "In10.Cu" signal "GND4")
		(24 "In11.Cu" signal "IN4")
		(26 "In12.Cu" signal "GND5")
		(28 "In13.Cu" signal "IN5")
		(30 "In14.Cu" signal "GND6")
		(32 "In15.Cu" signal "IN6")
		(34 "In16.Cu" signal "GND7")
		(2 "B.Cu" signal "BOTTOM")
		(9 "F.Adhes" user "F.Adhesive")
		(11 "B.Adhes" user "B.Adhesive")
		(13 "F.Paste" user "Package Geometry/Pastemask Top")
		(15 "B.Paste" user "Package Geometry/Pastemask Bottom")
		(5 "F.SilkS" user "Ref Des/Silkscreen Top")
		(7 "B.SilkS" user "Ref Des/Silkscreen Bottom")
		(1 "F.Mask" user "Board Geometry/Soldermask Top")
		(3 "B.Mask" user "Board Geometry/Soldermask Bottom")
		(17 "Dwgs.User" user "User.Drawings")
		(19 "Cmts.User" user "User.Comments")
		(21 "Eco1.User" user "User.Eco1")
		(23 "Eco2.User" user "User.Eco2")
		(25 "Edge.Cuts" user "Board Geometry/Outline")
		(27 "Margin" user)
		(31 "F.CrtYd" user "Package Geometry/Place Bound Top")
		(29 "B.CrtYd" user "Package Geometry/Place Bound Bottom")
		(35 "F.Fab" user "Ref Des/Assembly Top")
		(33 "B.Fab" user "Ref Des/Assembly Bottom")
	)
	(footprint ""
		(layer "F.Cu")
		(at 291.799772 -18.983452)
		(property "Reference" "R4182"
			(at 0 0 0)
			(layer "F.SilkS")
			(hide yes)
			(effects
				(font
					(size 1.27 1.27)
				)
			)
		)
		(property "Value" ""
			(at 0 0 0)
			(layer "F.Fab")
			(effects
				(font
					(size 1.27 1.27)
				)
			)
		)
		(duplicate_pad_numbers_are_jumpers no)
		(fp_line
			(start -0.7874 -0.4064)
			(end 0.7874 -0.4064)
			(stroke
				(width 0.1524)
				(type default)
			)
			(layer "F.SilkS")
		)
		(fp_line
			(start -0.7874 0.4064)
			(end -0.7874 -0.4064)
			(stroke
				(width 0.1524)
				(type default)
			)
			(layer "F.SilkS")
		)
		(fp_line
			(start 0.7874 -0.4064)
			(end 0.7874 0.4064)
			(stroke
				(width 0.1524)
				(type default)
			)
			(layer "F.SilkS")
		)
		(fp_line
			(start 0.7874 0.4064)
			(end -0.7874 0.4064)
			(stroke
				(width 0.1524)
				(type default)
			)
			(layer "F.SilkS")
		)
		(fp_line
			(start -0.67945 -0.305054)
			(end -0.12065 -0.305054)
			(stroke
				(width 0.1)
				(type default)
			)
			(layer "F.Fab")
		)
		(fp_line
			(start -0.67945 0.3048)
			(end -0.67945 -0.305054)
			(stroke
				(width 0.1)
				(type default)
			)
			(layer "F.Fab")
		)
		(fp_line
			(start -0.12065 -0.305054)
			(end -0.12065 -0.2794)
			(stroke
				(width 0.1)
				(type default)
			)
			(layer "F.Fab")
		)
		(fp_line
			(start -0.12065 -0.2794)
			(end 0.12065 -0.2794)
			(stroke
				(width 0.1)
				(type default)
			)
			(layer "F.Fab")
		)
		(fp_line
			(start -0.12065 0.2794)
			(end -0.12065 0.3048)
			(stroke
				(width 0.1)
				(type default)
			)
			(layer "F.Fab")
		)
		(fp_line
			(start -0.12065 0.3048)
			(end -0.67945 0.3048)
			(stroke
				(width 0.1)
				(type default)
			)
			(layer "F.Fab")
		)
		(fp_line
			(start 0.120396 0.2794)
			(end -0.12065 0.2794)
			(stroke
				(width 0.1)
				(type default)
			)
			(layer "F.Fab")
		)
		(fp_line
			(start 0.120396 0.3048)
			(end 0.120396 0.2794)
			(stroke
				(width 0.1)
				(type default)
			)
			(layer "F.Fab")
		)
		(fp_line
			(start 0.12065 -0.3048)
			(end 0.67945 -0.3048)
			(stroke
				(width 0.1)
				(type default)
			)
			(layer "F.Fab")
		)
		(fp_line
			(start 0.12065 -0.2794)
			(end 0.12065 -0.3048)
			(stroke
				(width 0.1)
				(type default)
			)
			(layer "F.Fab")
		)
		(fp_line
			(start 0.67945 -0.3048)
			(end 0.67945 0.3048)
			(stroke
				(width 0.1)
				(type default)
			)
			(layer "F.Fab")
		)
		(fp_line
			(start 0.67945 0.3048)
			(end 0.120396 0.3048)
			(stroke
				(width 0.1)
				(type default)
			)
			(layer "F.Fab")
		)
		(pad "1" smd circle
			(at -0.40005 0)
			(size 0 0)
			(layers "F.Cu" "F.Mask" "F.Paste")
			(net "SMB_LM75_1_3V3AUX_SDA")
		)
		(pad "2" smd circle
			(at 0.40005 0)
			(size 0 0)
			(layers "F.Cu" "F.Mask" "F.Paste")
			(net "SMB_LM75_1_3V3AUX_SDA_R1")
		)
	)
	(footprint ""
		(layer "F.Cu")
		(at 370.225066 -424.002962 90)
		(property "Reference" "R4191"
			(at 0 0 90)
			(layer "F.SilkS")
			(hide yes)
			(effects
				(font
					(size 1.27 1.27)
				)
			)
		)
		(property "Value" ""
			(at 0 0 90)
			(layer "F.Fab")
			(effects
				(font
					(size 1.27 1.27)
				)
			)
		)
		(duplicate_pad_numbers_are_jumpers no)
		(fp_line
			(start 0.7874 -0.4064)
			(end 0.7874 0.4064)
			(stroke
				(width 0.1524)
				(type default)
			)
			(layer "F.SilkS")
		)
		(fp_line
			(start -0.7874 -0.4064)
			(end 0.7874 -0.4064)
			(stroke
				(width 0.1524)
				(type default)
			)
			(layer "F.SilkS")
		)
		(fp_line
			(start 0.7874 0.4064)
			(end -0.7874 0.4064)
			(stroke
				(width 0.1524)
				(type default)
			)
			(layer "F.SilkS")
		)
		(fp_line
			(start -0.7874 0.4064)
			(end -0.7874 -0.4064)
			(stroke
				(width 0.1524)
				(type default)
			)
			(layer "F.SilkS")
		)
		(fp_line
			(start -0.12065 -0.305054)
			(end -0.12065 -0.2794)
			(stroke
				(width 0.1)
				(type default)
			)
			(layer "F.Fab")
		)
		(fp_line
			(start -0.67945 -0.305054)
			(end -0.12065 -0.305054)
			(stroke
				(width 0.1)
				(type default)
			)
			(layer "F.Fab")
		)
		(fp_line
			(start 0.67945 -0.3048)
			(end 0.67945 0.3048)
			(stroke
				(width 0.1)
				(type default)
			)
			(layer "F.Fab")
		)
		(fp_line
			(start 0.12065 -0.3048)
			(end 0.67945 -0.3048)
			(stroke
				(width 0.1)
				(type default)
			)
			(layer "F.Fab")
		)
		(fp_line
			(start 0.12065 -0.2794)
			(end 0.12065 -0.3048)
			(stroke
				(width 0.1)
				(type default)
			)
			(layer "F.Fab")
		)
		(fp_line
			(start -0.12065 -0.2794)
			(end 0.12065 -0.2794)
			(stroke
				(width 0.1)
				(type default)
			)
			(layer "F.Fab")
		)
		(fp_line
			(start 0.120396 0.2794)
			(end -0.12065 0.2794)
			(stroke
				(width 0.1)
				(type default)
			)
			(layer "F.Fab")
		)
		(fp_line
			(start -0.12065 0.2794)
			(end -0.12065 0.3048)
			(stroke
				(width 0.1)
				(type default)
			)
			(layer "F.Fab")
		)
		(fp_line
			(start 0.67945 0.3048)
			(end 0.120396 0.3048)
			(stroke
				(width 0.1)
				(type default)
			)
			(layer "F.Fab")
		)
		(fp_line
			(start 0.120396 0.3048)
			(end 0.120396 0.2794)
			(stroke
				(width 0.1)
				(type default)
			)
			(layer "F.Fab")
		)
		(fp_line
			(start -0.12065 0.3048)
			(end -0.67945 0.3048)
			(stroke
				(width 0.1)
				(type default)
			)
			(layer "F.Fab")
		)
		(fp_line
			(start -0.67945 0.3048)
			(end -0.67945 -0.305054)
			(stroke
				(width 0.1)
				(type default)
			)
			(layer "F.Fab")
		)
		(pad "1" smd circle
			(at -0.40005 0 90)
			(size 0 0)
			(layers "F.Cu" "F.Mask" "F.Paste")
			(net "U270_0_ADD2")
		)
		(pad "2" smd circle
			(at 0.40005 0 90)
			(size 0 0)
			(layers "F.Cu" "F.Mask" "F.Paste")
			(net "GND")
		)
	)
)
